(kicad_pcb
	(version 20260206)
	(generator "pcbnew")
	(generator_version "10.0")
	(general
		(thickness 1.6)
		(legacy_teardrops no)
	)
	(paper "A4")
	(title_block
		(title "pdpb — Lightning_PDPB_BRD.brd")
		(comment 1 "Lightning (Wiwynn / Facebook NVMe JBOF) / footprints 1020-1026 of 1140")
	)
	(layers
		(0 "F.Cu" signal "TOP")
		(4 "In1.Cu" signal "L2GND")
		(6 "In2.Cu" signal "L3")
		(8 "In3.Cu" signal "L4VCC")
		(10 "In4.Cu" signal "L5VCC")
		(12 "In5.Cu" signal "L6")
		(14 "In6.Cu" signal "L7GND")
		(2 "B.Cu" signal "BOTTOM")
		(9 "F.Adhes" user "F.Adhesive")
		(11 "B.Adhes" user "B.Adhesive")
		(13 "F.Paste" user "Package Geometry/Pastemask Top")
		(15 "B.Paste" user "Package Geometry/Pastemask Bottom")
		(5 "F.SilkS" user "Ref Des/Silkscreen Top")
		(7 "B.SilkS" user "Ref Des/Silkscreen Bottom")
		(1 "F.Mask" user "Board Geometry/Soldermask Top")
		(3 "B.Mask" user "Board Geometry/Soldermask Bottom")
		(17 "Dwgs.User" user "User.Drawings")
		(19 "Cmts.User" user "User.Comments")
		(21 "Eco1.User" user "User.Eco1")
		(23 "Eco2.User" user "User.Eco2")
		(25 "Edge.Cuts" user "Board Geometry/Outline")
		(27 "Margin" user)
		(31 "F.CrtYd" user "Package Geometry/Place Bound Top")
		(29 "B.CrtYd" user "Package Geometry/Place Bound Bottom")
		(35 "F.Fab" user "Ref Des/Assembly Top")
		(33 "B.Fab" user "Ref Des/Assembly Bottom")
	)
	(footprint ""
		(layer "F.Cu")
		(at 19.4945 -368.073178 180)
		(property "Reference" "R9855"
			(at 0 0 180)
			(layer "F.SilkS")
			(hide yes)
			(effects
				(font
					(size 1.27 1.27)
				)
			)
		)
		(property "Value" "0R2J-2-GP"
			(at 0.064008 -3.993896 180)
			(unlocked yes)
			(layer "F.Fab")
			(hide yes)
			(effects
				(font
					(size 1.016 1.016)
					(thickness 0.1524)
				)
			)
		)
		(property "Device Type" "R402H16"
			(at 0.064008 -5.517896 180)
			(unlocked yes)
			(layer "F.Fab")
			(hide yes)
			(effects
				(font
					(size 1.016 1.016)
					(thickness 0.1524)
				)
			)
		)
		(duplicate_pad_numbers_are_jumpers no)
		(fp_line
			(start 0.508 -0.9398)
			(end -0.508 -0.9398)
			(stroke
				(width 0.1524)
				(type default)
			)
			(layer "F.SilkS")
		)
		(fp_line
			(start -0.508 -0.9398)
			(end -0.508 0.9398)
			(stroke
				(width 0.1524)
				(type default)
			)
			(layer "F.SilkS")
		)
		(fp_rect
			(start -0.508 0.9398)
			(end 0.508 -0.9398)
			(stroke
				(width 0)
				(type default)
			)
			(fill no)
			(layer "F.CrtYd")
		)
		(fp_rect
			(start -0.508 0.9398)
			(end 0.508 -0.9398)
			(stroke
				(width 0)
				(type default)
			)
			(fill no)
			(layer "F.Fab")
		)
		(pad "1" smd custom
			(at 0 -0.4445 180)
			(size 0.1397 0.1397)
			(layers "F.Cu" "F.Mask" "F.Paste")
			(net "SSD_ACT_DR11_R")
			(options
				(clearance outline)
				(anchor circle)
			)
			(primitives
				(gr_poly
					(pts
						(arc
							(start -0.1778 -0.2794)
							(mid -0.249642 -0.249642)
							(end -0.2794 -0.1778)
						)
						(arc
							(start -0.2794 0.1778)
							(mid -0.249642 0.249642)
							(end -0.1778 0.2794)
						)
						(arc
							(start 0.1778 0.2794)
							(mid 0.249642 0.249642)
							(end 0.2794 0.1778)
						)
						(arc
							(start 0.2794 -0.1778)
							(mid 0.249642 -0.249642)
							(end 0.1778 -0.2794)
						)
					)
					(width 0)
					(fill yes)
				)
			)
		)
		(pad "2" smd custom
			(at 0 0.4445 180)
			(size 0.1397 0.1397)
			(layers "F.Cu" "F.Mask" "F.Paste")
			(net "SSD_ACT_DR11")
			(options
				(clearance outline)
				(anchor circle)
			)
			(primitives
				(gr_poly
					(pts
						(arc
							(start -0.1778 -0.2794)
							(mid -0.249642 -0.249642)
							(end -0.2794 -0.1778)
						)
						(arc
							(start -0.2794 0.1778)
							(mid -0.249642 0.249642)
							(end -0.1778 0.2794)
						)
						(arc
							(start 0.1778 0.2794)
							(mid 0.249642 0.249642)
							(end 0.2794 0.1778)
						)
						(arc
							(start 0.2794 -0.1778)
							(mid 0.249642 -0.249642)
							(end 0.1778 -0.2794)
						)
					)
					(width 0)
					(fill yes)
				)
			)
		)
	)
	(footprint ""
		(layer "F.Cu")
		(at 30.6832 -112.4712)
		(property "Reference" "SR1118"
			(at 0 0 0)
			(layer "F.SilkS")
			(hide yes)
			(effects
				(font
					(size 1.27 1.27)
				)
			)
		)
		(property "Value" "4K7R2F-GP"
			(at 0.064008 -3.993896 0)
			(unlocked yes)
			(layer "F.Fab")
			(hide yes)
			(effects
				(font
					(size 1.016 1.016)
					(thickness 0.1524)
				)
			)
		)
		(property "Device Type" "R402H16"
			(at 0.064008 -5.517896 0)
			(unlocked yes)
			(layer "F.Fab")
			(hide yes)
			(effects
				(font
					(size 1.016 1.016)
					(thickness 0.1524)
				)
			)
		)
		(duplicate_pad_numbers_are_jumpers no)
		(fp_line
			(start -0.508 -0.9398)
			(end -0.508 0.9398)
			(stroke
				(width 0.1524)
				(type default)
			)
			(layer "F.SilkS")
		)
		(fp_line
			(start 0.508 -0.9398)
			(end -0.508 -0.9398)
			(stroke
				(width 0.1524)
				(type default)
			)
			(layer "F.SilkS")
		)
		(fp_rect
			(start -0.508 0.9398)
			(end 0.508 -0.9398)
			(stroke
				(width 0)
				(type default)
			)
			(fill no)
			(layer "F.CrtYd")
		)
		(fp_rect
			(start -0.508 0.9398)
			(end 0.508 -0.9398)
			(stroke
				(width 0)
				(type default)
			)
			(fill no)
			(layer "F.Fab")
		)
		(pad "1" smd custom
			(at 0 -0.4445)
			(size 0.1397 0.1397)
			(layers "F.Cu" "F.Mask" "F.Paste")
			(net "DUALPORTEN#13")
			(options
				(clearance outline)
				(anchor circle)
			)
			(primitives
				(gr_poly
					(pts
						(arc
							(start -0.1778 -0.2794)
							(mid -0.249642 -0.249642)
							(end -0.2794 -0.1778)
						)
						(arc
							(start -0.2794 0.1778)
							(mid -0.249642 0.249642)
							(end -0.1778 0.2794)
						)
						(arc
							(start 0.1778 0.2794)
							(mid 0.249642 0.249642)
							(end 0.2794 0.1778)
						)
						(arc
							(start 0.2794 -0.1778)
							(mid 0.249642 -0.249642)
							(end 0.1778 -0.2794)
						)
					)
					(width 0)
					(fill yes)
				)
			)
		)
		(pad "2" smd custom
			(at 0 0.4445)
			(size 0.1397 0.1397)
			(layers "F.Cu" "F.Mask" "F.Paste")
			(net "GND")
			(options
				(clearance outline)
				(anchor circle)
			)
			(primitives
				(gr_poly
					(pts
						(arc
							(start -0.1778 -0.2794)
							(mid -0.249642 -0.249642)
							(end -0.2794 -0.1778)
						)
						(arc
							(start -0.2794 0.1778)
							(mid -0.249642 0.249642)
							(end -0.1778 0.2794)
						)
						(arc
							(start 0.1778 0.2794)
							(mid 0.249642 0.249642)
							(end 0.2794 0.1778)
						)
						(arc
							(start 0.2794 -0.1778)
							(mid 0.249642 -0.249642)
							(end 0.1778 -0.2794)
						)
					)
					(width 0)
					(fill yes)
				)
			)
		)
	)
	(footprint ""
		(layer "F.Cu")
		(at 99.314 -219.456 180)
		(property "Reference" "R9098"
			(at 0 0 180)
			(layer "F.SilkS")
			(hide yes)
			(effects
				(font
					(size 1.27 1.27)
				)
			)
		)
		(property "Value" "27R2F-GP"
			(at 0.064008 -3.993896 180)
			(unlocked yes)
			(layer "F.Fab")
			(hide yes)
			(effects
				(font
					(size 1.016 1.016)
					(thickness 0.1524)
				)
			)
		)
		(property "Device Type" "R402H16"
			(at 0.064008 -5.517896 180)
			(unlocked yes)
			(layer "F.Fab")
			(hide yes)
			(effects
				(font
					(size 1.016 1.016)
					(thickness 0.1524)
				)
			)
		)
		(duplicate_pad_numbers_are_jumpers no)
		(fp_line
			(start 0.508 -0.9398)
			(end -0.508 -0.9398)
			(stroke
				(width 0.1524)
				(type default)
			)
			(layer "F.SilkS")
		)
		(fp_line
			(start -0.508 -0.9398)
			(end -0.508 0.9398)
			(stroke
				(width 0.1524)
				(type default)
			)
			(layer "F.SilkS")
		)
		(fp_rect
			(start -0.508 0.9398)
			(end 0.508 -0.9398)
			(stroke
				(width 0)
				(type default)
			)
			(fill no)
			(layer "F.CrtYd")
		)
		(fp_rect
			(start -0.508 0.9398)
			(end 0.508 -0.9398)
			(stroke
				(width 0)
				(type default)
			)
			(fill no)
			(layer "F.Fab")
		)
		(pad "1" smd custom
			(at 0 -0.4445 180)
			(size 0.1397 0.1397)
			(layers "F.Cu" "F.Mask" "F.Paste")
			(net "PE_CLK_100M_DR7_2_R_N")
			(options
				(clearance outline)
				(anchor circle)
			)
			(primitives
				(gr_poly
					(pts
						(arc
							(start -0.1778 -0.2794)
							(mid -0.249642 -0.249642)
							(end -0.2794 -0.1778)
						)
						(arc
							(start -0.2794 0.1778)
							(mid -0.249642 0.249642)
							(end -0.1778 0.2794)
						)
						(arc
							(start 0.1778 0.2794)
							(mid 0.249642 0.249642)
							(end 0.2794 0.1778)
						)
						(arc
							(start 0.2794 -0.1778)
							(mid 0.249642 -0.249642)
							(end 0.1778 -0.2794)
						)
					)
					(width 0)
					(fill yes)
				)
			)
		)
		(pad "2" smd custom
			(at 0 0.4445 180)
			(size 0.1397 0.1397)
			(layers "F.Cu" "F.Mask" "F.Paste")
			(net "PE_CLK100M_DR7_2_N")
			(options
				(clearance outline)
				(anchor circle)
			)
			(primitives
				(gr_poly
					(pts
						(arc
							(start -0.1778 -0.2794)
							(mid -0.249642 -0.249642)
							(end -0.2794 -0.1778)
						)
						(arc
							(start -0.2794 0.1778)
							(mid -0.249642 0.249642)
							(end -0.1778 0.2794)
						)
						(arc
							(start 0.1778 0.2794)
							(mid 0.249642 0.249642)
							(end 0.2794 0.1778)
						)
						(arc
							(start 0.2794 -0.1778)
							(mid 0.249642 -0.249642)
							(end 0.1778 -0.2794)
						)
					)
					(width 0)
					(fill yes)
				)
			)
		)
	)
	(footprint ""
		(layer "F.Cu")
		(at 87.503 -92.964)
		(property "Reference" "R9120"
			(at 0 0 0)
			(layer "F.SilkS")
			(hide yes)
			(effects
				(font
					(size 1.27 1.27)
				)
			)
		)
		(property "Value" "27R2F-GP"
			(at 0.064008 -3.993896 0)
			(unlocked yes)
			(layer "F.Fab")
			(hide yes)
			(effects
				(font
					(size 1.016 1.016)
					(thickness 0.1524)
				)
			)
		)
		(property "Device Type" "R402H16"
			(at 0.064008 -5.517896 0)
			(unlocked yes)
			(layer "F.Fab")
			(hide yes)
			(effects
				(font
					(size 1.016 1.016)
					(thickness 0.1524)
				)
			)
		)
		(duplicate_pad_numbers_are_jumpers no)
		(fp_line
			(start -0.508 -0.9398)
			(end -0.508 0.9398)
			(stroke
				(width 0.1524)
				(type default)
			)
			(layer "F.SilkS")
		)
		(fp_line
			(start 0.508 -0.9398)
			(end -0.508 -0.9398)
			(stroke
				(width 0.1524)
				(type default)
			)
			(layer "F.SilkS")
		)
		(fp_rect
			(start -0.508 0.9398)
			(end 0.508 -0.9398)
			(stroke
				(width 0)
				(type default)
			)
			(fill no)
			(layer "F.CrtYd")
		)
		(fp_rect
			(start -0.508 0.9398)
			(end 0.508 -0.9398)
			(stroke
				(width 0)
				(type default)
			)
			(fill no)
			(layer "F.Fab")
		)
		(pad "1" smd custom
			(at 0 -0.4445)
			(size 0.1397 0.1397)
			(layers "F.Cu" "F.Mask" "F.Paste")
			(net "PE_CLK_100M_DR9_2_R_N")
			(options
				(clearance outline)
				(anchor circle)
			)
			(primitives
				(gr_poly
					(pts
						(arc
							(start -0.1778 -0.2794)
							(mid -0.249642 -0.249642)
							(end -0.2794 -0.1778)
						)
						(arc
							(start -0.2794 0.1778)
							(mid -0.249642 0.249642)
							(end -0.1778 0.2794)
						)
						(arc
							(start 0.1778 0.2794)
							(mid 0.249642 0.249642)
							(end 0.2794 0.1778)
						)
						(arc
							(start 0.2794 -0.1778)
							(mid 0.249642 -0.249642)
							(end 0.1778 -0.2794)
						)
					)
					(width 0)
					(fill yes)
				)
			)
		)
		(pad "2" smd custom
			(at 0 0.4445)
			(size 0.1397 0.1397)
			(layers "F.Cu" "F.Mask" "F.Paste")
			(net "PE_CLK100M_DR9_2_N")
			(options
				(clearance outline)
				(anchor circle)
			)
			(primitives
				(gr_poly
					(pts
						(arc
							(start -0.1778 -0.2794)
							(mid -0.249642 -0.249642)
							(end -0.2794 -0.1778)
						)
						(arc
							(start -0.2794 0.1778)
							(mid -0.249642 0.249642)
							(end -0.1778 0.2794)
						)
						(arc
							(start 0.1778 0.2794)
							(mid 0.249642 0.249642)
							(end 0.2794 0.1778)
						)
						(arc
							(start 0.2794 -0.1778)
							(mid 0.249642 -0.249642)
							(end 0.1778 -0.2794)
						)
					)
					(width 0)
					(fill yes)
				)
			)
		)
	)
	(footprint ""
		(layer "F.Cu")
		(at 21.336 -265.303 180)
		(property "Reference" "R9924"
			(at 0 0 180)
			(layer "F.SilkS")
			(hide yes)
			(effects
				(font
					(size 1.27 1.27)
				)
			)
		)
		(property "Value" "47KR2J-2-GP"
			(at 0.064008 -3.993896 180)
			(unlocked yes)
			(layer "F.Fab")
			(hide yes)
			(effects
				(font
					(size 1.016 1.016)
					(thickness 0.1524)
				)
			)
		)
		(property "Device Type" "R402H16"
			(at 0.064008 -5.517896 180)
			(unlocked yes)
			(layer "F.Fab")
			(hide yes)
			(effects
				(font
					(size 1.016 1.016)
					(thickness 0.1524)
				)
			)
		)
		(duplicate_pad_numbers_are_jumpers no)
		(fp_line
			(start 0.508 -0.9398)
			(end -0.508 -0.9398)
			(stroke
				(width 0.1524)
				(type default)
			)
			(layer "F.SilkS")
		)
		(fp_line
			(start -0.508 -0.9398)
			(end -0.508 0.9398)
			(stroke
				(width 0.1524)
				(type default)
			)
			(layer "F.SilkS")
		)
		(fp_rect
			(start -0.508 0.9398)
			(end 0.508 -0.9398)
			(stroke
				(width 0)
				(type default)
			)
			(fill no)
			(layer "F.CrtYd")
		)
		(fp_rect
			(start -0.508 0.9398)
			(end 0.508 -0.9398)
			(stroke
				(width 0)
				(type default)
			)
			(fill no)
			(layer "F.Fab")
		)
		(pad "1" smd custom
			(at 0 -0.4445 180)
			(size 0.1397 0.1397)
			(layers "F.Cu" "F.Mask" "F.Paste")
			(net "P3V3")
			(options
				(clearance outline)
				(anchor circle)
			)
			(primitives
				(gr_poly
					(pts
						(arc
							(start -0.1778 -0.2794)
							(mid -0.249642 -0.249642)
							(end -0.2794 -0.1778)
						)
						(arc
							(start -0.2794 0.1778)
							(mid -0.249642 0.249642)
							(end -0.1778 0.2794)
						)
						(arc
							(start 0.1778 0.2794)
							(mid 0.249642 0.249642)
							(end 0.2794 0.1778)
						)
						(arc
							(start 0.2794 -0.1778)
							(mid 0.249642 -0.249642)
							(end 0.1778 -0.2794)
						)
					)
					(width 0)
					(fill yes)
				)
			)
		)
		(pad "2" smd custom
			(at 0 0.4445 180)
			(size 0.1397 0.1397)
			(layers "F.Cu" "F.Mask" "F.Paste")
			(net "ATTN_LED_DR12_N")
			(options
				(clearance outline)
				(anchor circle)
			)
			(primitives
				(gr_poly
					(pts
						(arc
							(start -0.1778 -0.2794)
							(mid -0.249642 -0.249642)
							(end -0.2794 -0.1778)
						)
						(arc
							(start -0.2794 0.1778)
							(mid -0.249642 0.249642)
							(end -0.1778 0.2794)
						)
						(arc
							(start 0.1778 0.2794)
							(mid 0.249642 0.249642)
							(end 0.2794 0.1778)
						)
						(arc
							(start 0.2794 -0.1778)
							(mid 0.249642 -0.249642)
							(end 0.1778 -0.2794)
						)
					)
					(width 0)
					(fill yes)
				)
			)
		)
	)
	(footprint ""
		(layer "F.Cu")
		(at 100.33 -313.817 180)
		(property "Reference" "R9100"
			(at 0 0 180)
			(layer "F.SilkS")
			(hide yes)
			(effects
				(font
					(size 1.27 1.27)
				)
			)
		)
		(property "Value" "27R2F-GP"
			(at 0.064008 -3.993896 180)
			(unlocked yes)
			(layer "F.Fab")
			(hide yes)
			(effects
				(font
					(size 1.016 1.016)
					(thickness 0.1524)
				)
			)
		)
		(property "Device Type" "R402H16"
			(at 0.064008 -5.517896 180)
			(unlocked yes)
			(layer "F.Fab")
			(hide yes)
			(effects
				(font
					(size 1.016 1.016)
					(thickness 0.1524)
				)
			)
		)
		(duplicate_pad_numbers_are_jumpers no)
		(fp_line
			(start 0.508 -0.9398)
			(end -0.508 -0.9398)
			(stroke
				(width 0.1524)
				(type default)
			)
			(layer "F.SilkS")
		)
		(fp_line
			(start -0.508 -0.9398)
			(end -0.508 0.9398)
			(stroke
				(width 0.1524)
				(type default)
			)
			(layer "F.SilkS")
		)
		(fp_rect
			(start -0.508 0.9398)
			(end 0.508 -0.9398)
			(stroke
				(width 0)
				(type default)
			)
			(fill no)
			(layer "F.CrtYd")
		)
		(fp_rect
			(start -0.508 0.9398)
			(end 0.508 -0.9398)
			(stroke
				(width 0)
				(type default)
			)
			(fill no)
			(layer "F.Fab")
		)
		(pad "1" smd custom
			(at 0 -0.4445 180)
			(size 0.1397 0.1397)
			(layers "F.Cu" "F.Mask" "F.Paste")
			(net "PE_CLK_100M_DR6_2_R_P")
			(options
				(clearance outline)
				(anchor circle)
			)
			(primitives
				(gr_poly
					(pts
						(arc
							(start -0.1778 -0.2794)
							(mid -0.249642 -0.249642)
							(end -0.2794 -0.1778)
						)
						(arc
							(start -0.2794 0.1778)
							(mid -0.249642 0.249642)
							(end -0.1778 0.2794)
						)
						(arc
							(start 0.1778 0.2794)
							(mid 0.249642 0.249642)
							(end 0.2794 0.1778)
						)
						(arc
							(start 0.2794 -0.1778)
							(mid 0.249642 -0.249642)
							(end 0.1778 -0.2794)
						)
					)
					(width 0)
					(fill yes)
				)
			)
		)
		(pad "2" smd custom
			(at 0 0.4445 180)
			(size 0.1397 0.1397)
			(layers "F.Cu" "F.Mask" "F.Paste")
			(net "PE_CLK100M_DR6_2_P")
			(options
				(clearance outline)
				(anchor circle)
			)
			(primitives
				(gr_poly
					(pts
						(arc
							(start -0.1778 -0.2794)
							(mid -0.249642 -0.249642)
							(end -0.2794 -0.1778)
						)
						(arc
							(start -0.2794 0.1778)
							(mid -0.249642 0.249642)
							(end -0.1778 0.2794)
						)
						(arc
							(start 0.1778 0.2794)
							(mid 0.249642 0.249642)
							(end 0.2794 0.1778)
						)
						(arc
							(start 0.2794 -0.1778)
							(mid 0.249642 -0.249642)
							(end 0.1778 -0.2794)
						)
					)
					(width 0)
					(fill yes)
				)
			)
		)
	)
	(footprint ""
		(layer "F.Cu")
		(at 43.1292 -196.9516)
		(property "Reference" "R9247"
			(at 0 0 0)
			(layer "F.SilkS")
			(hide yes)
			(effects
				(font
					(size 1.27 1.27)
				)
			)
		)
		(property "Value" "2R2010F-GP"
			(at 0.0762 -4.5466 0)
			(unlocked yes)
			(layer "F.Fab")
			(hide yes)
			(effects
				(font
					(size 1.016 1.016)
					(thickness 0.1524)
				)
			)
		)
		(property "Device Type" "R2010H26"
			(at 0.0762 -6.1468 0)
			(unlocked yes)
			(layer "F.Fab")
			(hide yes)
			(effects
				(font
					(size 1.016 1.016)
					(thickness 0.1524)
				)
			)
		)
		(duplicate_pad_numbers_are_jumpers no)
		(fp_line
			(start -3.302 -1.651)
			(end -3.302 1.651)
			(stroke
				(width 0.1524)
				(type default)
			)
			(layer "F.SilkS")
		)
		(fp_line
			(start -3.302 1.651)
			(end 3.302 1.651)
			(stroke
				(width 0.1524)
				(type default)
			)
			(layer "F.SilkS")
		)
		(fp_line
			(start 3.302 -1.651)
			(end -3.302 -1.651)
			(stroke
				(width 0.1524)
				(type default)
			)
			(layer "F.SilkS")
		)
		(fp_line
			(start 3.302 1.651)
			(end 3.302 -1.651)
			(stroke
				(width 0.1524)
				(type default)
			)
			(layer "F.SilkS")
		)
		(fp_rect
			(start -3.3782 1.7272)
			(end 3.3782 -1.7272)
			(stroke
				(width 0)
				(type default)
			)
			(fill no)
			(layer "F.CrtYd")
		)
		(fp_poly
			(pts
				(xy 3.3782 -1.7272) (xy -3.3782 -1.7272) (xy -3.3782 1.7272) (xy 3.3782 1.7272)
			)
			(stroke
				(width 0)
				(type default)
			)
			(fill no)
			(layer "F.Fab")
		)
		(pad "1" smd rect
			(at -2.3495 0)
			(size 1.143 2.794)
			(layers "F.Cu" "F.Mask" "F.Paste")
			(net "P12V_SSD8")
		)
		(pad "2" smd rect
			(at 2.3495 0)
			(size 1.143 2.794)
			(layers "F.Cu" "F.Mask" "F.Paste")
			(net "12V_PRECH_SSD8")
		)
	)
)
